(kicad_pcb
	(version 20241229)
	(generator "pcbnew")
	(generator_version "9.0")
	(general
		(thickness 1.294)
		(legacy_teardrops no)
	)
	(paper "A3")
	(title_block
		(title "Kintex 410T devboard")
		(date "2024-04-03")
		(rev "1.1.2")
		(comment 9 "footprints 463-469 of 975")
	)
	(layers
		(0 "F.Cu" mixed)
		(4 "In1.Cu" power)
		(6 "In2.Cu" power)
		(8 "In3.Cu" mixed)
		(10 "In4.Cu" power)
		(12 "In5.Cu" mixed)
		(14 "In6.Cu" power)
		(16 "In7.Cu" mixed)
		(18 "In8.Cu" power)
		(2 "B.Cu" mixed)
		(9 "F.Adhes" user "F.Adhesive")
		(11 "B.Adhes" user "B.Adhesive")
		(13 "F.Paste" user)
		(15 "B.Paste" user)
		(5 "F.SilkS" user "F.Silkscreen")
		(7 "B.SilkS" user "B.Silkscreen")
		(1 "F.Mask" user)
		(3 "B.Mask" user)
		(17 "Dwgs.User" user "User.Drawings")
		(19 "Cmts.User" user "User.Comments")
		(21 "Eco1.User" user "User.Eco1")
		(23 "Eco2.User" user "User.Eco2")
		(25 "Edge.Cuts" user)
		(27 "Margin" user)
		(31 "F.CrtYd" user "F.Courtyard")
		(29 "B.CrtYd" user "B.Courtyard")
		(35 "F.Fab" user)
		(33 "B.Fab" user)
	)
	(footprint "antmicro-footprints:R_0402_1005Metric"
		(layer "F.Cu")
		(at 242.599 115.404 90)
		(descr "Resistor SMD 0402")
		(tags "resistor SMD 0402")
		(property "Reference" "R349"
			(at -1.496 -0.549 90)
			(unlocked yes)
			(layer "F.SilkS")
			(effects
				(font
					(size 0.7 0.7)
					(thickness 0.15)
				)
				(justify left bottom)
			)
		)
		(property "Value" "R_0R_0402"
			(at 0 1.4 90)
			(layer "F.Fab")
			(effects
				(font
					(size 0.7 0.7)
					(thickness 0.15)
				)
				(justify left bottom)
			)
		)
		(property "Description" "SMD Chip Resistor, Jumper, 0 ohm, 100 mW, 0402 [1005 Metric], Thick Film, General Purpose"
			(at 0 0 90)
			(layer "F.Fab")
			(hide yes)
			(effects
				(font
					(size 1.27 1.27)
					(thickness 0.15)
				)
			)
		)
		(property "Author" "Antmicro"
			(at 358.003 -127.195 0)
			(layer "F.Fab")
			(hide yes)
			(effects
				(font
					(size 1 1)
					(thickness 0.15)
				)
			)
		)
		(property "Current" "1A"
			(at 358.003 -127.195 0)
			(layer "F.Fab")
			(hide yes)
			(effects
				(font
					(size 1 1)
					(thickness 0.15)
				)
			)
		)
		(property "License" "Apache-2.0"
			(at 358.003 -127.195 0)
			(layer "F.Fab")
			(hide yes)
			(effects
				(font
					(size 1 1)
					(thickness 0.15)
				)
			)
		)
		(property "MPN" "ERJ2GE0R00X"
			(at 358.003 -127.195 0)
			(layer "F.Fab")
			(hide yes)
			(effects
				(font
					(size 1 1)
					(thickness 0.15)
				)
			)
		)
		(property "Manufacturer" "Panasonic"
			(at 358.003 -127.195 0)
			(layer "F.Fab")
			(hide yes)
			(effects
				(font
					(size 1 1)
					(thickness 0.15)
				)
			)
		)
		(property "Tolerance" ""
			(at 358.003 -127.195 0)
			(layer "F.Fab")
			(hide yes)
			(effects
				(font
					(size 1 1)
					(thickness 0.15)
				)
			)
		)
		(property "Val" "0R"
			(at 358.003 -127.195 0)
			(layer "F.Fab")
			(hide yes)
			(effects
				(font
					(size 1 1)
					(thickness 0.15)
				)
			)
		)
		(sheetname "USB PHY")
		(sheetfile "usb-phy.kicad_sch")
		(attr smd)
		(fp_rect
			(start -0.925 -0.47)
			(end 0.925 0.47)
			(stroke
				(width 0.05)
				(type default)
			)
			(fill no)
			(layer "F.CrtYd")
		)
		(fp_rect
			(start -0.5 -0.25)
			(end 0.5 0.25)
			(stroke
				(width 0.15)
				(type solid)
			)
			(fill no)
			(layer "F.Fab")
		)
		(pad "1" smd roundrect
			(at -0.48 0 90)
			(size 0.59 0.64)
			(layers "F.Cu" "F.Mask" "F.Paste")
			(roundrect_rratio 0.25)
			(net 570 "/FPGA Bank 12 & 13/USB_USER.VBUS_PEN")
			(pintype "passive")
		)
		(pad "2" smd roundrect
			(at 0.48 0 90)
			(size 0.59 0.64)
			(layers "F.Cu" "F.Mask" "F.Paste")
			(roundrect_rratio 0.25)
			(net 385 "Net-(U43-EN)")
			(pintype "passive")
		)
	)
	(footprint "antmicro-footprints:TP_1206_SMD_RCW-0C"
		(layer "F.Cu")
		(at 167.78 164.65)
		(property "Reference" "TP9"
			(at 2.77 0.95 90)
			(layer "F.SilkS")
			(effects
				(font
					(size 0.7 0.7)
					(thickness 0.15)
				)
				(justify left bottom)
			)
		)
		(property "Value" "TP_1206_SMD_RCW-0C"
			(at -4.68 2.25 0)
			(layer "F.Fab")
			(effects
				(font
					(size 0.7 0.7)
					(thickness 0.15)
				)
				(justify left bottom)
			)
		)
		(property "Description" "Circuit Probe Pad, SMD, Test Point, 1206"
			(at 0 0 0)
			(layer "F.Fab")
			(hide yes)
			(effects
				(font
					(size 1.27 1.27)
					(thickness 0.15)
				)
			)
		)
		(property "Author" "Antmicro"
			(at 0 0 0)
			(layer "F.Fab")
			(hide yes)
			(effects
				(font
					(size 1 1)
					(thickness 0.15)
				)
			)
		)
		(property "License" "Apache-2.0"
			(at 0 0 0)
			(layer "F.Fab")
			(hide yes)
			(effects
				(font
					(size 1 1)
					(thickness 0.15)
				)
			)
		)
		(property "MPN" "RCW-0C"
			(at 0 0 0)
			(layer "F.Fab")
			(hide yes)
			(effects
				(font
					(size 1 1)
					(thickness 0.15)
				)
			)
		)
		(property "Manufacturer" "TE Connectivity"
			(at 0 0 0)
			(layer "F.Fab")
			(hide yes)
			(effects
				(font
					(size 1 1)
					(thickness 0.15)
				)
			)
		)
		(sheetfile "k410t-devboard.kicad_sch")
		(attr smd)
		(fp_line
			(start -1.779 -0.981)
			(end -1.779 -0.479)
			(stroke
				(width 0.15)
				(type solid)
			)
			(layer "F.SilkS")
		)
		(fp_line
			(start -1.779 -0.981)
			(end -1.279 -0.981)
			(stroke
				(width 0.15)
				(type solid)
			)
			(layer "F.SilkS")
		)
		(fp_line
			(start -1.779 0.482)
			(end -1.779 0.98)
			(stroke
				(width 0.15)
				(type solid)
			)
			(layer "F.SilkS")
		)
		(fp_line
			(start -1.779 0.98)
			(end -1.279 0.98)
			(stroke
				(width 0.15)
				(type solid)
			)
			(layer "F.SilkS")
		)
		(fp_line
			(start 1.78 -0.981)
			(end 1.281 -0.981)
			(stroke
				(width 0.15)
				(type solid)
			)
			(layer "F.SilkS")
		)
		(fp_line
			(start 1.78 -0.981)
			(end 1.78 -0.479)
			(stroke
				(width 0.15)
				(type solid)
			)
			(layer "F.SilkS")
		)
		(fp_line
			(start 1.78 0.982)
			(end 1.281 0.982)
			(stroke
				(width 0.15)
				(type solid)
			)
			(layer "F.SilkS")
		)
		(fp_line
			(start 1.78 0.982)
			(end 1.78 0.482)
			(stroke
				(width 0.15)
				(type solid)
			)
			(layer "F.SilkS")
		)
		(fp_rect
			(start -2.101 -1.314)
			(end 2.1 1.312)
			(stroke
				(width 0.05)
				(type solid)
			)
			(fill no)
			(layer "F.CrtYd")
		)
		(fp_rect
			(start -1.601 -0.814)
			(end 1.6 0.812)
			(stroke
				(width 0.15)
				(type solid)
			)
			(fill no)
			(layer "F.Fab")
		)
		(pad "1" smd rect
			(at 0 0)
			(size 3.4 1.8)
			(layers "F.Cu" "F.Mask" "F.Paste")
			(net 1 "GND")
			(pinfunction "1")
			(pintype "passive")
		)
	)
	(footprint "antmicro-footprints:NetTie-2_SMD_Pad0.127mm"
		(layer "F.Cu")
		(at 258.36 120.04 -90)
		(descr "Net tie, 2 pin, 0.127mm  SMD pads")
		(tags "net tie")
		(property "Reference" "NT25"
			(at -0.128 -1.345 90)
			(layer "F.SilkS")
			(hide yes)
			(effects
				(font
					(size 0.7 0.7)
					(thickness 0.15)
				)
				(justify right bottom)
			)
		)
		(property "Value" "Net-Tie_2"
			(at 0 1.199 90)
			(layer "F.Fab")
			(effects
				(font
					(size 0.7 0.7)
					(thickness 0.15)
				)
				(justify right bottom)
			)
		)
		(property "Description" "Net tie, 2 pins"
			(at 0 0 270)
			(layer "F.Fab")
			(hide yes)
			(effects
				(font
					(size 1.27 1.27)
					(thickness 0.15)
				)
			)
		)
		(property "Author" "Antmicro"
			(at 138.32 378.4 0)
			(layer "F.Fab")
			(hide yes)
			(effects
				(font
					(size 1 1)
					(thickness 0.15)
				)
			)
		)
		(property "License" "Apache-2.0"
			(at 138.32 378.4 0)
			(layer "F.Fab")
			(hide yes)
			(effects
				(font
					(size 1 1)
					(thickness 0.15)
				)
			)
		)
		(property "MPN" ""
			(at 138.32 378.4 0)
			(layer "F.Fab")
			(hide yes)
			(effects
				(font
					(size 1 1)
					(thickness 0.15)
				)
			)
		)
		(property "Manufacturer" ""
			(at 138.32 378.4 0)
			(layer "F.Fab")
			(hide yes)
			(effects
				(font
					(size 1 1)
					(thickness 0.15)
				)
			)
		)
		(sheetname "DC-DC Converters")
		(sheetfile "dc-dc.kicad_sch")
		(attr exclude_from_pos_files)
		(net_tie_pad_groups "1, 2")
		(fp_poly
			(pts
				(xy -0.0635 -0.0635) (xy 0.0625 -0.0635) (xy 0.0625 0.0635) (xy -0.0635 0.0635)
			)
			(stroke
				(width 0)
				(type solid)
			)
			(fill yes)
			(layer "F.Cu")
		)
		(pad "1" smd roundrect
			(at -0.127 0 90)
			(size 0.127 0.127)
			(layers "F.Cu")
			(roundrect_rratio 0.5)
			(chamfer_ratio 0)
			(chamfer top_left bottom_left)
			(net 1 "GND")
			(pinfunction "1")
			(pintype "passive")
		)
		(pad "2" smd roundrect
			(at 0.126 0 270)
			(size 0.127 0.127)
			(layers "F.Cu")
			(roundrect_rratio 0.5)
			(chamfer_ratio 0)
			(chamfer top_left bottom_left)
			(net 1213 "/DC-DC Converters/SENSE_5V_N")
			(pinfunction "2")
			(pintype "passive")
		)
	)
	(footprint "antmicro-footprints:C_0402_1005Metric"
		(layer "F.Cu")
		(at 198.3625 88.3365 -90)
		(descr "Capacitor SMD 0402")
		(tags "capacitor SMD 0402")
		(property "Reference" "C292"
			(at -1.8865 0.4625 90)
			(layer "F.SilkS")
			(effects
				(font
					(size 0.7 0.7)
					(thickness 0.15)
				)
				(justify right bottom)
			)
		)
		(property "Value" "C_10u_0402"
			(at 0 1.4 90)
			(layer "F.Fab")
			(effects
				(font
					(size 0.7 0.7)
					(thickness 0.15)
				)
				(justify right bottom)
			)
		)
		(property "Description" "SMD Multilayer Ceramic Capacitor, 10 µF, 6.3 V, 0402 [1005 Metric], ± 20%, X5R, CC Series"
			(at 0 0 270)
			(layer "F.Fab")
			(hide yes)
			(effects
				(font
					(size 1.27 1.27)
					(thickness 0.15)
				)
			)
		)
		(property "Author" "Antmicro"
			(at 110.026 286.699 0)
			(layer "F.Fab")
			(hide yes)
			(effects
				(font
					(size 1 1)
					(thickness 0.15)
				)
			)
		)
		(property "Dielectric" ""
			(at 110.026 286.699 0)
			(layer "F.Fab")
			(hide yes)
			(effects
				(font
					(size 1 1)
					(thickness 0.15)
				)
			)
		)
		(property "License" "Apache-2.0"
			(at 110.026 286.699 0)
			(layer "F.Fab")
			(hide yes)
			(effects
				(font
					(size 1 1)
					(thickness 0.15)
				)
			)
		)
		(property "MPN" "CC0402MRX5R5BB106"
			(at 110.026 286.699 0)
			(layer "F.Fab")
			(hide yes)
			(effects
				(font
					(size 1 1)
					(thickness 0.15)
				)
			)
		)
		(property "Manufacturer" "YAGEO"
			(at 110.026 286.699 0)
			(layer "F.Fab")
			(hide yes)
			(effects
				(font
					(size 1 1)
					(thickness 0.15)
				)
			)
		)
		(property "Val" "10u"
			(at 110.026 286.699 0)
			(layer "F.Fab")
			(hide yes)
			(effects
				(font
					(size 1 1)
					(thickness 0.15)
				)
			)
		)
		(property "Voltage" ""
			(at 110.026 286.699 0)
			(layer "F.Fab")
			(hide yes)
			(effects
				(font
					(size 1 1)
					(thickness 0.15)
				)
			)
		)
		(sheetname "HDMI + Ethernet")
		(sheetfile "hdmi-ethernet.kicad_sch")
		(attr smd)
		(fp_rect
			(start -0.925 -0.47)
			(end 0.925 0.47)
			(stroke
				(width 0.05)
				(type default)
			)
			(fill no)
			(layer "F.CrtYd")
		)
		(fp_line
			(start -0.494 0.248)
			(end -0.494 -0.25)
			(stroke
				(width 0.15)
				(type solid)
			)
			(layer "F.Fab")
		)
		(fp_line
			(start 0.504 0.248)
			(end -0.494 0.248)
			(stroke
				(width 0.15)
				(type solid)
			)
			(layer "F.Fab")
		)
		(fp_line
			(start -0.494 -0.25)
			(end 0.504 -0.25)
			(stroke
				(width 0.15)
				(type solid)
			)
			(layer "F.Fab")
		)
		(fp_line
			(start 0.504 -0.25)
			(end 0.504 0.248)
			(stroke
				(width 0.15)
				(type solid)
			)
			(layer "F.Fab")
		)
		(pad "1" smd roundrect
			(at -0.48 0 270)
			(size 0.59 0.64)
			(layers "F.Cu" "F.Mask" "F.Paste")
			(roundrect_rratio 0.25)
			(net 1 "GND")
			(pintype "passive")
		)
		(pad "2" smd roundrect
			(at 0.48 0 270)
			(size 0.59 0.64)
			(layers "F.Cu" "F.Mask" "F.Paste")
			(roundrect_rratio 0.25)
			(net 727 "+1V2")
			(pintype "passive")
		)
	)
	(footprint "antmicro-footprints:R_0402_1005Metric"
		(layer "F.Cu")
		(at 218.4 148.8)
		(descr "Resistor SMD 0402")
		(tags "resistor SMD 0402")
		(property "Reference" "R234"
			(at -3.6 0.35 0)
			(layer "F.SilkS")
			(effects
				(font
					(size 0.7 0.7)
					(thickness 0.15)
				)
				(justify left bottom)
			)
		)
		(property "Value" "R_10R_0402"
			(at 0 1.4 0)
			(layer "F.Fab")
			(effects
				(font
					(size 0.7 0.7)
					(thickness 0.15)
				)
				(justify left bottom)
			)
		)
		(property "Description" "SMD Chip Resistor, 10 ohm, ± 1%, 62.5 mW, 0402 [1005 Metric], Thick Film, General Purpose"
			(at 0 0 0)
			(layer "F.Fab")
			(hide yes)
			(effects
				(font
					(size 1.27 1.27)
					(thickness 0.15)
				)
			)
		)
		(property "Author" "Antmicro"
			(at 0 0 0)
			(layer "F.Fab")
			(hide yes)
			(effects
				(font
					(size 1 1)
					(thickness 0.15)
				)
			)
		)
		(property "License" "Apache-2.0"
			(at 0 0 0)
			(layer "F.Fab")
			(hide yes)
			(effects
				(font
					(size 1 1)
					(thickness 0.15)
				)
			)
		)
		(property "MPN" "CR0402-FX-10R0GLF"
			(at 0 0 0)
			(layer "F.Fab")
			(hide yes)
			(effects
				(font
					(size 1 1)
					(thickness 0.15)
				)
			)
		)
		(property "Manufacturer" "Bourns"
			(at 0 0 0)
			(layer "F.Fab")
			(hide yes)
			(effects
				(font
					(size 1 1)
					(thickness 0.15)
				)
			)
		)
		(property "Tolerance" "1%"
			(at 0 0 0)
			(layer "F.Fab")
			(hide yes)
			(effects
				(font
					(size 1 1)
					(thickness 0.15)
				)
			)
		)
		(property "Val" "10R"
			(at 0 0 0)
			(layer "F.Fab")
			(hide yes)
			(effects
				(font
					(size 1 1)
					(thickness 0.15)
				)
			)
		)
		(sheetname "HDMI + Ethernet")
		(sheetfile "hdmi-ethernet.kicad_sch")
		(attr smd)
		(fp_rect
			(start -0.925 -0.47)
			(end 0.925 0.47)
			(stroke
				(width 0.05)
				(type default)
			)
			(fill no)
			(layer "F.CrtYd")
		)
		(fp_rect
			(start -0.5 -0.25)
			(end 0.5 0.25)
			(stroke
				(width 0.15)
				(type solid)
			)
			(fill no)
			(layer "F.Fab")
		)
		(pad "1" smd roundrect
			(at -0.48 0)
			(size 0.59 0.64)
			(layers "F.Cu" "F.Mask" "F.Paste")
			(roundrect_rratio 0.25)
			(net 516 "/FPGA Bank 18 & 32/ETH_RMII.REFCLK")
			(pintype "passive")
		)
		(pad "2" smd roundrect
			(at 0.48 0)
			(size 0.59 0.64)
			(layers "F.Cu" "F.Mask" "F.Paste")
			(roundrect_rratio 0.25)
			(net 951 "/HDMI + Ethernet/ETH_PHY_REFCLK")
			(pintype "passive")
		)
	)
	(footprint "antmicro-footprints:C_0402_1005Metric"
		(layer "F.Cu")
		(at 158.8 155.7 -90)
		(descr "Capacitor SMD 0402")
		(tags "capacitor SMD 0402")
		(property "Reference" "C400"
			(at 0.75 -0.4 90)
			(layer "F.SilkS")
			(effects
				(font
					(size 0.7 0.7)
					(thickness 0.15)
				)
				(justify right bottom)
			)
		)
		(property "Value" "C_100n_0402"
			(at 0 1.4 90)
			(layer "F.Fab")
			(effects
				(font
					(size 0.7 0.7)
					(thickness 0.15)
				)
				(justify right bottom)
			)
		)
		(property "Description" "SMD Multilayer Ceramic Capacitor, 0.1 µF, 50 V, 0402 [1005 Metric], ± 10%, X5R, GRM Series"
			(at 0 0 270)
			(layer "F.Fab")
			(hide yes)
			(effects
				(font
					(size 1.27 1.27)
					(thickness 0.15)
				)
			)
		)
		(property "Author" "Antmicro"
			(at 3.1 314.5 0)
			(layer "F.Fab")
			(hide yes)
			(effects
				(font
					(size 1 1)
					(thickness 0.15)
				)
			)
		)
		(property "Dielectric" "X5R"
			(at 3.1 314.5 0)
			(layer "F.Fab")
			(hide yes)
			(effects
				(font
					(size 1 1)
					(thickness 0.15)
				)
			)
		)
		(property "License" "Apache-2.0"
			(at 3.1 314.5 0)
			(layer "F.Fab")
			(hide yes)
			(effects
				(font
					(size 1 1)
					(thickness 0.15)
				)
			)
		)
		(property "MPN" "GRM155R61H104KE14D"
			(at 3.1 314.5 0)
			(layer "F.Fab")
			(hide yes)
			(effects
				(font
					(size 1 1)
					(thickness 0.15)
				)
			)
		)
		(property "Manufacturer" "Murata"
			(at 3.1 314.5 0)
			(layer "F.Fab")
			(hide yes)
			(effects
				(font
					(size 1 1)
					(thickness 0.15)
				)
			)
		)
		(property "Val" "100n"
			(at 3.1 314.5 0)
			(layer "F.Fab")
			(hide yes)
			(effects
				(font
					(size 1 1)
					(thickness 0.15)
				)
			)
		)
		(property "Voltage" "50V"
			(at 3.1 314.5 0)
			(layer "F.Fab")
			(hide yes)
			(effects
				(font
					(size 1 1)
					(thickness 0.15)
				)
			)
		)
		(sheetname "DC-DC Converters")
		(sheetfile "dc-dc.kicad_sch")
		(attr smd)
		(fp_rect
			(start -0.925 -0.47)
			(end 0.925 0.47)
			(stroke
				(width 0.05)
				(type default)
			)
			(fill no)
			(layer "F.CrtYd")
		)
		(fp_line
			(start -0.494 0.248)
			(end -0.494 -0.25)
			(stroke
				(width 0.15)
				(type solid)
			)
			(layer "F.Fab")
		)
		(fp_line
			(start 0.504 0.248)
			(end -0.494 0.248)
			(stroke
				(width 0.15)
				(type solid)
			)
			(layer "F.Fab")
		)
		(fp_line
			(start -0.494 -0.25)
			(end 0.504 -0.25)
			(stroke
				(width 0.15)
				(type solid)
			)
			(layer "F.Fab")
		)
		(fp_line
			(start 0.504 -0.25)
			(end 0.504 0.248)
			(stroke
				(width 0.15)
				(type solid)
			)
			(layer "F.Fab")
		)
		(pad "1" smd roundrect
			(at -0.48 0 270)
			(size 0.59 0.64)
			(layers "F.Cu" "F.Mask" "F.Paste")
			(roundrect_rratio 0.25)
			(net 1 "GND")
			(pintype "passive")
		)
		(pad "2" smd roundrect
			(at 0.48 0 270)
			(size 0.59 0.64)
			(layers "F.Cu" "F.Mask" "F.Paste")
			(roundrect_rratio 0.25)
			(net 25 "+1V35")
			(pintype "passive")
		)
	)
	(footprint "antmicro-footprints:C_0402_1005Metric"
		(layer "F.Cu")
		(at 255.95 141.915 90)
		(descr "Capacitor SMD 0402")
		(tags "capacitor SMD 0402")
		(property "Reference" "C221"
			(at -3.585 0.4 90)
			(layer "F.SilkS")
			(effects
				(font
					(size 0.7 0.7)
					(thickness 0.15)
				)
				(justify left bottom)
			)
		)
		(property "Value" "C_10u_0402"
			(at 0 1.4 90)
			(layer "F.Fab")
			(effects
				(font
					(size 0.7 0.7)
					(thickness 0.15)
				)
				(justify left bottom)
			)
		)
		(property "Description" "SMD Multilayer Ceramic Capacitor, 10 µF, 6.3 V, 0402 [1005 Metric], ± 20%, X5R, CC Series"
			(at 0 0 90)
			(layer "F.Fab")
			(hide yes)
			(effects
				(font
					(size 1.27 1.27)
					(thickness 0.15)
				)
			)
		)
		(property "Author" "Antmicro"
			(at 397.865 -114.035 0)
			(layer "F.Fab")
			(hide yes)
			(effects
				(font
					(size 1 1)
					(thickness 0.15)
				)
			)
		)
		(property "Dielectric" ""
			(at 397.865 -114.035 0)
			(layer "F.Fab")
			(hide yes)
			(effects
				(font
					(size 1 1)
					(thickness 0.15)
				)
			)
		)
		(property "License" "Apache-2.0"
			(at 397.865 -114.035 0)
			(layer "F.Fab")
			(hide yes)
			(effects
				(font
					(size 1 1)
					(thickness 0.15)
				)
			)
		)
		(property "MPN" "CC0402MRX5R5BB106"
			(at 397.865 -114.035 0)
			(layer "F.Fab")
			(hide yes)
			(effects
				(font
					(size 1 1)
					(thickness 0.15)
				)
			)
		)
		(property "Manufacturer" "YAGEO"
			(at 397.865 -114.035 0)
			(layer "F.Fab")
			(hide yes)
			(effects
				(font
					(size 1 1)
					(thickness 0.15)
				)
			)
		)
		(property "Val" "10u"
			(at 397.865 -114.035 0)
			(layer "F.Fab")
			(hide yes)
			(effects
				(font
					(size 1 1)
					(thickness 0.15)
				)
			)
		)
		(property "Voltage" ""
			(at 397.865 -114.035 0)
			(layer "F.Fab")
			(hide yes)
			(effects
				(font
					(size 1 1)
					(thickness 0.15)
				)
			)
		)
		(sheetname "USB PHY")
		(sheetfile "usb-phy.kicad_sch")
		(attr smd)
		(fp_rect
			(start -0.925 -0.47)
			(end 0.925 0.47)
			(stroke
				(width 0.05)
				(type default)
			)
			(fill no)
			(layer "F.CrtYd")
		)
		(fp_line
			(start 0.504 -0.25)
			(end 0.504 0.248)
			(stroke
				(width 0.15)
				(type solid)
			)
			(layer "F.Fab")
		)
		(fp_line
			(start -0.494 -0.25)
			(end 0.504 -0.25)
			(stroke
				(width 0.15)
				(type solid)
			)
			(layer "F.Fab")
		)
		(fp_line
			(start 0.504 0.248)
			(end -0.494 0.248)
			(stroke
				(width 0.15)
				(type solid)
			)
			(layer "F.Fab")
		)
		(fp_line
			(start -0.494 0.248)
			(end -0.494 -0.25)
			(stroke
				(width 0.15)
				(type solid)
			)
			(layer "F.Fab")
		)
		(pad "1" smd roundrect
			(at -0.48 0 90)
			(size 0.59 0.64)
			(layers "F.Cu" "F.Mask" "F.Paste")
			(roundrect_rratio 0.25)
			(net 1 "GND")
			(pintype "passive")
		)
		(pad "2" smd roundrect
			(at 0.48 0 90)
			(size 0.59 0.64)
			(layers "F.Cu" "F.Mask" "F.Paste")
			(roundrect_rratio 0.25)
			(net 707 "/USB PHY/FTDI_3V3")
			(pintype "passive")
		)
	)
)
